#ISCELL
  logical_power cad_note *
  *
#ISCELL
  mstr_misc dns *
  *
#ISCELL
  pure_quanta quanta_title_block_c *
  *
#ISCELL
  logical_power universal_gnd *
  page56_i10
#ISCELL
  logical_power universal_gnd *
  page56_i14
#CELL
  pure_quanta nb695gdz *
  page56_i15
#CELL
  pure_quanta q_cap *
  page56_i16
#ISCELL
  logical_power universal_gnd *
  page56_i17
#CELL
  pure_quanta q_res *
  page56_i18
#CELL
  pure_quanta q_cap *
  page56_i19
#ISCELL
  logical_power vccaux15 *
  page56_i2
#CELL
  pure_quanta q_cap *
  page56_i23
#CELL
  pure_quanta q_cap *
  page56_i24
#CELL
  pure_quanta q_cap *
  page56_i25
#ISCELL
  logical_power universal_gnd *
  page56_i27
#CELL
  pure_quanta q_cap *
  page56_i28
#CELL
  pure_quanta q_cap *
  page56_i29
#ISCELL
  logical_power vccaux15 *
  page56_i30
#CELL
  pure_quanta q_inductor *
  page56_i34
#CELL
  pure_quanta q_inductor *
  page56_i37
#ISCELL
  logical_power vccaux15 *
  page56_i38
#ISCELL
  logical_power universal_gnd *
  page56_i4
#CELL
  pure_quanta q_cap *
  page56_i43
#CELL
  pure_quanta q_cap *
  page56_i44
#ISCELL
  logical_power vccaux15 *
  page56_i45
#ISCELL
  logical_power vccaux15 *
  page56_i46
#CELL
  pure_quanta q_res *
  page56_i47
#CELL
  pure_quanta q_res *
  page56_i48
#ISCELL
  logical_power vccaux15 *
  page56_i49
#ISCELL
  logical_power universal_gnd *
  page56_i5
#ISCELL
  logical_power vccaux15 *
  page56_i50
#CELL
  pure_quanta q_cap *
  page56_i51
#ISCELL
  logical_power universal_gnd *
  page56_i52
#ISCELL
  standard offpage *
  page56_i53
#CELL
  pure_quanta q_res *
  page56_i54
#CELL
  pure_quanta q_res *
  page56_i55
#ISCELL
  standard offpage *
  page56_i56
#ISCELL
  logical_power universal_gnd *
  page56_i57
#CELL
  pure_quanta q_cap *
  page56_i58
#ISCELL
  standard offpage *
  page56_i59
#ISCELL
  standard offpage *
  page56_i60
#ISCELL
  logical_power universal_gnd *
  page56_i61
#ISCELL
  logical_power universal_gnd *
  page56_i63
#CELL
  pure_quanta q_cap *
  page56_i64
#CELL
  pure_quanta 74lvc1g08gw *
  page56_i66
#CELL
  pure_quanta q_cap *
  page56_i7
#ISCELL
  standard offpage *
  page56_i70
#CELL
  pure_quanta q_res *
  page56_i71
#CELL
  pure_quanta q_res *
  page56_i72
#ISCELL
  standard offpage *
  page56_i73
#ISCELL
  logical_power universal_power *
  page56_i74
#CELL
  pure_quanta q_res *
  page56_i8
#ISCELL
  logical_power vccaux15 *
  page56_i9
